(kicad_pcb
	(version 20241229)
	(generator "pcbnew")
	(generator_version "9.0")
	(general
		(thickness 1.294)
		(legacy_teardrops no)
	)
	(paper "A3")
	(title_block
		(title "Kintex 410T devboard")
		(date "2024-04-03")
		(rev "1.1.2")
		(comment 9 "footprints 166-169 of 975")
	)
	(layers
		(0 "F.Cu" mixed)
		(4 "In1.Cu" power)
		(6 "In2.Cu" power)
		(8 "In3.Cu" mixed)
		(10 "In4.Cu" power)
		(12 "In5.Cu" mixed)
		(14 "In6.Cu" power)
		(16 "In7.Cu" mixed)
		(18 "In8.Cu" power)
		(2 "B.Cu" mixed)
		(9 "F.Adhes" user "F.Adhesive")
		(11 "B.Adhes" user "B.Adhesive")
		(13 "F.Paste" user)
		(15 "B.Paste" user)
		(5 "F.SilkS" user "F.Silkscreen")
		(7 "B.SilkS" user "B.Silkscreen")
		(1 "F.Mask" user)
		(3 "B.Mask" user)
		(17 "Dwgs.User" user "User.Drawings")
		(19 "Cmts.User" user "User.Comments")
		(21 "Eco1.User" user "User.Eco1")
		(23 "Eco2.User" user "User.Eco2")
		(25 "Edge.Cuts" user)
		(27 "Margin" user)
		(31 "F.CrtYd" user "F.Courtyard")
		(29 "B.CrtYd" user "B.Courtyard")
		(35 "F.Fab" user)
		(33 "B.Fab" user)
	)
	(footprint "antmicro-footprints:C_0402_1005Metric"
		(layer "F.Cu")
		(at 256.345 133.735 180)
		(descr "Capacitor SMD 0402")
		(tags "capacitor SMD 0402")
		(property "Reference" "C229"
			(at -2.205 3.835 0)
			(layer "F.SilkS")
			(effects
				(font
					(size 0.7 0.7)
					(thickness 0.15)
				)
				(justify right bottom)
			)
		)
		(property "Value" "C_10u_0402"
			(at 0 1.4 0)
			(layer "F.Fab")
			(effects
				(font
					(size 0.7 0.7)
					(thickness 0.15)
				)
				(justify right bottom)
			)
		)
		(property "Description" "SMD Multilayer Ceramic Capacitor, 10 µF, 6.3 V, 0402 [1005 Metric], ± 20%, X5R, CC Series"
			(at 0 0 180)
			(layer "F.Fab")
			(hide yes)
			(effects
				(font
					(size 1.27 1.27)
					(thickness 0.15)
				)
			)
		)
		(property "Author" "Antmicro"
			(at 512.69 267.47 0)
			(layer "F.Fab")
			(hide yes)
			(effects
				(font
					(size 1 1)
					(thickness 0.15)
				)
			)
		)
		(property "Dielectric" ""
			(at 512.69 267.47 0)
			(layer "F.Fab")
			(hide yes)
			(effects
				(font
					(size 1 1)
					(thickness 0.15)
				)
			)
		)
		(property "License" "Apache-2.0"
			(at 512.69 267.47 0)
			(layer "F.Fab")
			(hide yes)
			(effects
				(font
					(size 1 1)
					(thickness 0.15)
				)
			)
		)
		(property "MPN" "CC0402MRX5R5BB106"
			(at 512.69 267.47 0)
			(layer "F.Fab")
			(hide yes)
			(effects
				(font
					(size 1 1)
					(thickness 0.15)
				)
			)
		)
		(property "Manufacturer" "YAGEO"
			(at 512.69 267.47 0)
			(layer "F.Fab")
			(hide yes)
			(effects
				(font
					(size 1 1)
					(thickness 0.15)
				)
			)
		)
		(property "Val" "10u"
			(at 512.69 267.47 0)
			(layer "F.Fab")
			(hide yes)
			(effects
				(font
					(size 1 1)
					(thickness 0.15)
				)
			)
		)
		(property "Voltage" ""
			(at 512.69 267.47 0)
			(layer "F.Fab")
			(hide yes)
			(effects
				(font
					(size 1 1)
					(thickness 0.15)
				)
			)
		)
		(sheetname "USB PHY")
		(sheetfile "usb-phy.kicad_sch")
		(attr smd)
		(fp_rect
			(start -0.925 -0.47)
			(end 0.925 0.47)
			(stroke
				(width 0.05)
				(type default)
			)
			(fill no)
			(layer "F.CrtYd")
		)
		(fp_line
			(start 0.504 0.248)
			(end -0.494 0.248)
			(stroke
				(width 0.15)
				(type solid)
			)
			(layer "F.Fab")
		)
		(fp_line
			(start 0.504 -0.25)
			(end 0.504 0.248)
			(stroke
				(width 0.15)
				(type solid)
			)
			(layer "F.Fab")
		)
		(fp_line
			(start -0.494 0.248)
			(end -0.494 -0.25)
			(stroke
				(width 0.15)
				(type solid)
			)
			(layer "F.Fab")
		)
		(fp_line
			(start -0.494 -0.25)
			(end 0.504 -0.25)
			(stroke
				(width 0.15)
				(type solid)
			)
			(layer "F.Fab")
		)
		(pad "1" smd roundrect
			(at -0.48 0 180)
			(size 0.59 0.64)
			(layers "F.Cu" "F.Mask" "F.Paste")
			(roundrect_rratio 0.25)
			(net 1 "GND")
			(pintype "passive")
		)
		(pad "2" smd roundrect
			(at 0.48 0 180)
			(size 0.59 0.64)
			(layers "F.Cu" "F.Mask" "F.Paste")
			(roundrect_rratio 0.25)
			(net 711 "/USB PHY/FTDI_VPLL")
			(pintype "passive")
		)
	)
	(footprint "antmicro-footprints:R_0402_1005Metric"
		(layer "F.Cu")
		(at 264.7 139.5 90)
		(descr "Resistor SMD 0402")
		(tags "resistor SMD 0402")
		(property "Reference" "R150"
			(at 33.25 -29.85 180)
			(layer "F.SilkS")
			(effects
				(font
					(size 0.7 0.7)
					(thickness 0.15)
				)
				(justify left bottom)
			)
		)
		(property "Value" "R_330R_0402"
			(at 0 1.4 90)
			(layer "F.Fab")
			(effects
				(font
					(size 0.7 0.7)
					(thickness 0.15)
				)
				(justify left bottom)
			)
		)
		(property "Description" "SMD Chip Resistor, 330 ohm, ± 1%, 62.5 mW, 0402 [1005 Metric], Thick Film, General Purpose"
			(at 0 0 90)
			(layer "F.Fab")
			(hide yes)
			(effects
				(font
					(size 1.27 1.27)
					(thickness 0.15)
				)
			)
		)
		(property "Author" "Antmicro"
			(at 404.2 -125.2 0)
			(layer "F.Fab")
			(hide yes)
			(effects
				(font
					(size 1 1)
					(thickness 0.15)
				)
			)
		)
		(property "License" "Apache-2.0"
			(at 404.2 -125.2 0)
			(layer "F.Fab")
			(hide yes)
			(effects
				(font
					(size 1 1)
					(thickness 0.15)
				)
			)
		)
		(property "MPN" "CR0402-FX-3300GLF"
			(at 404.2 -125.2 0)
			(layer "F.Fab")
			(hide yes)
			(effects
				(font
					(size 1 1)
					(thickness 0.15)
				)
			)
		)
		(property "Manufacturer" "Bourns"
			(at 404.2 -125.2 0)
			(layer "F.Fab")
			(hide yes)
			(effects
				(font
					(size 1 1)
					(thickness 0.15)
				)
			)
		)
		(property "Tolerance" "1%"
			(at 404.2 -125.2 0)
			(layer "F.Fab")
			(hide yes)
			(effects
				(font
					(size 1 1)
					(thickness 0.15)
				)
			)
		)
		(property "Val" "330R"
			(at 404.2 -125.2 0)
			(layer "F.Fab")
			(hide yes)
			(effects
				(font
					(size 1 1)
					(thickness 0.15)
				)
			)
		)
		(sheetname "USB PHY")
		(sheetfile "usb-phy.kicad_sch")
		(attr smd)
		(fp_rect
			(start -0.925 -0.47)
			(end 0.925 0.47)
			(stroke
				(width 0.05)
				(type default)
			)
			(fill no)
			(layer "F.CrtYd")
		)
		(fp_rect
			(start -0.5 -0.25)
			(end 0.5 0.25)
			(stroke
				(width 0.15)
				(type solid)
			)
			(fill no)
			(layer "F.Fab")
		)
		(pad "1" smd roundrect
			(at -0.48 0 90)
			(size 0.59 0.64)
			(layers "F.Cu" "F.Mask" "F.Paste")
			(roundrect_rratio 0.25)
			(net 790 "Net-(D26-A)")
			(pintype "passive")
		)
		(pad "2" smd roundrect
			(at 0.48 0 90)
			(size 0.59 0.64)
			(layers "F.Cu" "F.Mask" "F.Paste")
			(roundrect_rratio 0.25)
			(net 912 "/USB PHY/LED_TX0")
			(pintype "passive")
		)
	)
	(footprint "antmicro-footprints:C_0402_1005Metric"
		(layer "F.Cu")
		(at 193.7 169.249 -90)
		(descr "Capacitor SMD 0402")
		(tags "capacitor SMD 0402")
		(property "Reference" "C204"
			(at 0.801 -0.4 270)
			(layer "F.SilkS")
			(effects
				(font
					(size 0.7 0.7)
					(thickness 0.15)
				)
				(justify right bottom)
			)
		)
		(property "Value" "C_100n_0402"
			(at 0 1.4 90)
			(layer "F.Fab")
			(effects
				(font
					(size 0.7 0.7)
					(thickness 0.15)
				)
				(justify right bottom)
			)
		)
		(property "Description" "SMD Multilayer Ceramic Capacitor, 0.1 µF, 50 V, 0402 [1005 Metric], ± 10%, X5R, GRM Series"
			(at 0 0 270)
			(layer "F.Fab")
			(hide yes)
			(effects
				(font
					(size 1.27 1.27)
					(thickness 0.15)
				)
			)
		)
		(property "Author" "Antmicro"
			(at 24.451 362.949 0)
			(layer "F.Fab")
			(hide yes)
			(effects
				(font
					(size 1 1)
					(thickness 0.15)
				)
			)
		)
		(property "Dielectric" "X5R"
			(at 24.451 362.949 0)
			(layer "F.Fab")
			(hide yes)
			(effects
				(font
					(size 1 1)
					(thickness 0.15)
				)
			)
		)
		(property "License" "Apache-2.0"
			(at 24.451 362.949 0)
			(layer "F.Fab")
			(hide yes)
			(effects
				(font
					(size 1 1)
					(thickness 0.15)
				)
			)
		)
		(property "MPN" "GRM155R61H104KE14D"
			(at 24.451 362.949 0)
			(layer "F.Fab")
			(hide yes)
			(effects
				(font
					(size 1 1)
					(thickness 0.15)
				)
			)
		)
		(property "Manufacturer" "Murata"
			(at 24.451 362.949 0)
			(layer "F.Fab")
			(hide yes)
			(effects
				(font
					(size 1 1)
					(thickness 0.15)
				)
			)
		)
		(property "Val" "100n"
			(at 24.451 362.949 0)
			(layer "F.Fab")
			(hide yes)
			(effects
				(font
					(size 1 1)
					(thickness 0.15)
				)
			)
		)
		(property "Voltage" "50V"
			(at 24.451 362.949 0)
			(layer "F.Fab")
			(hide yes)
			(effects
				(font
					(size 1 1)
					(thickness 0.15)
				)
			)
		)
		(sheetname "Power supply")
		(sheetfile "power-supply.kicad_sch")
		(attr smd)
		(fp_rect
			(start -0.925 -0.47)
			(end 0.925 0.47)
			(stroke
				(width 0.05)
				(type default)
			)
			(fill no)
			(layer "F.CrtYd")
		)
		(fp_line
			(start -0.494 0.248)
			(end -0.494 -0.25)
			(stroke
				(width 0.15)
				(type solid)
			)
			(layer "F.Fab")
		)
		(fp_line
			(start 0.504 0.248)
			(end -0.494 0.248)
			(stroke
				(width 0.15)
				(type solid)
			)
			(layer "F.Fab")
		)
		(fp_line
			(start -0.494 -0.25)
			(end 0.504 -0.25)
			(stroke
				(width 0.15)
				(type solid)
			)
			(layer "F.Fab")
		)
		(fp_line
			(start 0.504 -0.25)
			(end 0.504 0.248)
			(stroke
				(width 0.15)
				(type solid)
			)
			(layer "F.Fab")
		)
		(pad "1" smd roundrect
			(at -0.48 0 270)
			(size 0.59 0.64)
			(layers "F.Cu" "F.Mask" "F.Paste")
			(roundrect_rratio 0.25)
			(net 1 "GND")
			(pintype "passive")
		)
		(pad "2" smd roundrect
			(at 0.48 0 270)
			(size 0.59 0.64)
			(layers "F.Cu" "F.Mask" "F.Paste")
			(roundrect_rratio 0.25)
			(net 700 "/Power supply/USB_PD_VBUS")
			(pintype "passive")
		)
	)
	(footprint "antmicro-footprints:R_0402_1005Metric"
		(layer "F.Cu")
		(at 154.3125 169.2 90)
		(descr "Resistor SMD 0402")
		(tags "resistor SMD 0402")
		(property "Reference" "R296"
			(at 0.1 -0.4625 90)
			(layer "F.SilkS")
			(effects
				(font
					(size 0.7 0.7)
					(thickness 0.15)
				)
				(justify left bottom)
			)
		)
		(property "Value" "R_0R_0402"
			(at 0 1.4 90)
			(layer "F.Fab")
			(effects
				(font
					(size 0.7 0.7)
					(thickness 0.15)
				)
				(justify left bottom)
			)
		)
		(property "Description" "SMD Chip Resistor, Jumper, 0 ohm, 100 mW, 0402 [1005 Metric], Thick Film, General Purpose"
			(at 0 0 90)
			(layer "F.Fab")
			(hide yes)
			(effects
				(font
					(size 1.27 1.27)
					(thickness 0.15)
				)
			)
		)
		(property "Author" "Antmicro"
			(at 323.5125 14.8875 0)
			(layer "F.Fab")
			(hide yes)
			(effects
				(font
					(size 1 1)
					(thickness 0.15)
				)
			)
		)
		(property "Current" "1A"
			(at 323.5125 14.8875 0)
			(layer "F.Fab")
			(hide yes)
			(effects
				(font
					(size 1 1)
					(thickness 0.15)
				)
			)
		)
		(property "License" "Apache-2.0"
			(at 323.5125 14.8875 0)
			(layer "F.Fab")
			(hide yes)
			(effects
				(font
					(size 1 1)
					(thickness 0.15)
				)
			)
		)
		(property "MPN" "ERJ2GE0R00X"
			(at 323.5125 14.8875 0)
			(layer "F.Fab")
			(hide yes)
			(effects
				(font
					(size 1 1)
					(thickness 0.15)
				)
			)
		)
		(property "Manufacturer" "Panasonic"
			(at 323.5125 14.8875 0)
			(layer "F.Fab")
			(hide yes)
			(effects
				(font
					(size 1 1)
					(thickness 0.15)
				)
			)
		)
		(property "Tolerance" ""
			(at 323.5125 14.8875 0)
			(layer "F.Fab")
			(hide yes)
			(effects
				(font
					(size 1 1)
					(thickness 0.15)
				)
			)
		)
		(property "Val" "0R"
			(at 323.5125 14.8875 0)
			(layer "F.Fab")
			(hide yes)
			(effects
				(font
					(size 1 1)
					(thickness 0.15)
				)
			)
		)
		(sheetname "DC-DC Converters")
		(sheetfile "dc-dc.kicad_sch")
		(attr smd)
		(fp_rect
			(start -0.925 -0.47)
			(end 0.925 0.47)
			(stroke
				(width 0.05)
				(type default)
			)
			(fill no)
			(layer "F.CrtYd")
		)
		(fp_rect
			(start -0.5 -0.25)
			(end 0.5 0.25)
			(stroke
				(width 0.15)
				(type solid)
			)
			(fill no)
			(layer "F.Fab")
		)
		(pad "1" smd roundrect
			(at -0.48 0 90)
			(size 0.59 0.64)
			(layers "F.Cu" "F.Mask" "F.Paste")
			(roundrect_rratio 0.25)
			(net 959 "/DC-DC Converters/FB1")
			(pintype "passive")
		)
		(pad "2" smd roundrect
			(at 0.48 0 90)
			(size 0.59 0.64)
			(layers "F.Cu" "F.Mask" "F.Paste")
			(roundrect_rratio 0.25)
			(net 733 "/DC-DC Converters/MGTAVCC_local")
			(pintype "passive")
		)
	)
)
